(kicad_pcb
	(version 20260206)
	(generator "pcbnew")
	(generator_version "10.0")
	(general
		(thickness 1.6)
		(legacy_teardrops no)
	)
	(paper "A4")
	(title_block
		(title "Wiwynn_Tioga_Pass_MB.brd")
		(comment 1 "Tioga Pass / footprints 588-593 of 4770")
	)
	(layers
		(0 "F.Cu" signal "TOP")
		(4 "In1.Cu" signal "L2GND")
		(6 "In2.Cu" signal "L3")
		(8 "In3.Cu" signal "L4GND")
		(10 "In4.Cu" signal "L5")
		(12 "In5.Cu" signal "L6GND")
		(14 "In6.Cu" signal "L7VCC")
		(16 "In7.Cu" signal "L8VCC")
		(18 "In8.Cu" signal "L9GND")
		(20 "In9.Cu" signal "L10")
		(22 "In10.Cu" signal "L11GND")
		(24 "In11.Cu" signal "L12")
		(26 "In12.Cu" signal "L13GND")
		(2 "B.Cu" signal "BOTTOM")
		(9 "F.Adhes" user "F.Adhesive")
		(11 "B.Adhes" user "B.Adhesive")
		(13 "F.Paste" user "Package Geometry/Pastemask Top")
		(15 "B.Paste" user "Package Geometry/Pastemask Bottom")
		(5 "F.SilkS" user "Ref Des/Silkscreen Top")
		(7 "B.SilkS" user "Ref Des/Silkscreen Bottom")
		(1 "F.Mask" user "Board Geometry/Soldermask Top")
		(3 "B.Mask" user "Board Geometry/Soldermask Bottom")
		(17 "Dwgs.User" user "User.Drawings")
		(19 "Cmts.User" user "User.Comments")
		(21 "Eco1.User" user "User.Eco1")
		(23 "Eco2.User" user "User.Eco2")
		(25 "Edge.Cuts" user "Board Geometry/Outline")
		(27 "Margin" user)
		(31 "F.CrtYd" user "Package Geometry/Place Bound Top")
		(29 "B.CrtYd" user "Package Geometry/Place Bound Bottom")
		(35 "F.Fab" user "Ref Des/Assembly Top")
		(33 "B.Fab" user "Ref Des/Assembly Bottom")
	)
	(footprint ""
		(layer "F.Cu")
		(at 485.5845 -31.684468 180)
		(property "Reference" "Y8F1"
			(at -0.8001 3.55727 180)
			(unlocked yes)
			(layer "F.SilkS")
			(effects
				(font
					(size 0.7874 0.5842)
					(thickness 0.1524)
				)
				(justify left)
			)
		)
		(property "Value" ""
			(at 0 0 180)
			(layer "F.Fab")
			(effects
				(font
					(size 1.27 1.27)
				)
			)
		)
		(duplicate_pad_numbers_are_jumpers no)
		(fp_circle
			(center -1.049782 -0.44323)
			(end -1.176782 -0.44323)
			(stroke
				(width 0.254)
				(type default)
			)
			(fill no)
			(layer "F.SilkS")
		)
		(fp_rect
			(start -0.499872 2.70002)
			(end 2.100072 -0.599948)
			(stroke
				(width 0)
				(type default)
			)
			(fill no)
			(layer "F.CrtYd")
		)
		(fp_line
			(start 2.100072 2.70002)
			(end -0.499872 2.70002)
			(stroke
				(width 0.1)
				(type default)
			)
			(layer "F.Fab")
		)
		(fp_line
			(start 2.100072 -0.599948)
			(end 2.100072 2.70002)
			(stroke
				(width 0.1)
				(type default)
			)
			(layer "F.Fab")
		)
		(fp_line
			(start -0.499872 2.70002)
			(end -0.499872 -0.599948)
			(stroke
				(width 0.1)
				(type default)
			)
			(layer "F.Fab")
		)
		(fp_line
			(start -0.499872 -0.599948)
			(end 2.100072 -0.599948)
			(stroke
				(width 0.1)
				(type default)
			)
			(layer "F.Fab")
		)
		(fp_circle
			(center -1.049782 -0.44323)
			(end -1.176782 -0.44323)
			(stroke
				(width 0.254)
				(type default)
			)
			(fill no)
			(layer "F.Fab")
		)
		(pad "1" smd rect
			(at 0 0 180)
			(size 1.0414 1.143)
			(layers "F.Cu" "F.Mask" "F.Paste")
			(net "XTAL_CK_MNG_IN")
		)
		(pad "2" smd rect
			(at 0 2.100072 180)
			(size 1.0414 1.143)
			(layers "F.Cu" "F.Mask" "F.Paste")
			(net "GND")
		)
		(pad "3" smd rect
			(at 1.6002 2.100072 180)
			(size 1.0414 1.143)
			(layers "F.Cu" "F.Mask" "F.Paste")
			(net "XTAL_CK_MNG_OUT")
		)
		(pad "4" smd rect
			(at 1.6002 0 180)
			(size 1.0414 1.143)
			(layers "F.Cu" "F.Mask" "F.Paste")
			(net "GND")
		)
	)
	(footprint ""
		(layer "F.Cu")
		(at 2.397506 -147.328382 90)
		(property "Reference" "EU1A1"
			(at 3.292348 -1.686306 0)
			(unlocked yes)
			(layer "F.SilkS")
			(effects
				(font
					(size 0.7874 0.5842)
					(thickness 0.1524)
				)
			)
		)
		(property "Value" ""
			(at 0 0 90)
			(layer "F.Fab")
			(effects
				(font
					(size 1.27 1.27)
				)
			)
		)
		(duplicate_pad_numbers_are_jumpers no)
		(fp_line
			(start 2.9718 -3.5052)
			(end 2.9718 3.429)
			(stroke
				(width 0.1524)
				(type default)
			)
			(layer "F.SilkS")
		)
		(fp_line
			(start -3.0099 -3.5052)
			(end 2.9718 -3.5052)
			(stroke
				(width 0.1524)
				(type default)
			)
			(layer "F.SilkS")
		)
		(fp_line
			(start 2.9718 3.429)
			(end -3.0099 3.429)
			(stroke
				(width 0.1524)
				(type default)
			)
			(layer "F.SilkS")
		)
		(fp_line
			(start -3.0099 3.429)
			(end -3.0099 -3.5052)
			(stroke
				(width 0.1524)
				(type default)
			)
			(layer "F.SilkS")
		)
		(fp_circle
			(center -3.057398 -2.678684)
			(end -3.057398 -2.551684)
			(stroke
				(width 0.254)
				(type default)
			)
			(fill no)
			(layer "F.SilkS")
		)
		(fp_poly
			(pts
				(xy -2.9972 -3.4925) (xy -2.9972 -2.6924) (xy -2.1971 -3.4925)
			)
			(stroke
				(width 0)
				(type default)
			)
			(fill yes)
			(layer "F.SilkS")
		)
		(fp_poly
			(pts
				(xy -2.549906 -3.050032) (xy -2.549906 3.050032) (xy 2.549906 3.050032) (xy 2.549906 -3.050032)
			)
			(stroke
				(width 0)
				(type default)
			)
			(fill no)
			(layer "F.CrtYd")
		)
		(fp_line
			(start 2.549906 -3.050032)
			(end 2.549906 3.050032)
			(stroke
				(width 0.1)
				(type default)
			)
			(layer "F.Fab")
		)
		(fp_line
			(start -2.549906 -3.050032)
			(end 2.549906 -3.050032)
			(stroke
				(width 0.1)
				(type default)
			)
			(layer "F.Fab")
		)
		(fp_line
			(start 2.549906 3.050032)
			(end -2.549906 3.050032)
			(stroke
				(width 0.1)
				(type default)
			)
			(layer "F.Fab")
		)
		(fp_line
			(start -2.549906 3.050032)
			(end -2.549906 -3.050032)
			(stroke
				(width 0.1)
				(type default)
			)
			(layer "F.Fab")
		)
		(fp_circle
			(center -3.057398 -2.678684)
			(end -3.057398 -2.551684)
			(stroke
				(width 0.254)
				(type default)
			)
			(fill no)
			(layer "F.Fab")
		)
		(pad "1" smd rect
			(at -2.39522 -2.279904 90)
			(size 0.7112 0.254)
			(layers "F.Cu" "F.Mask" "F.Paste")
			(net "PVDDQ_KLM")
		)
		(pad "2" smd rect
			(at -2.39522 -1.83007 90)
			(size 0.7112 0.254)
			(layers "F.Cu" "F.Mask" "F.Paste")
			(net "GND")
		)
		(pad "3" smd rect
			(at -2.39522 -1.379982 90)
			(size 0.7112 0.254)
			(layers "F.Cu" "F.Mask" "F.Paste")
			(net "VR_PVDDQ_KLM_PH2_VCIN")
		)
		(pad "4" smd rect
			(at -2.39522 -0.929894 90)
			(size 0.7112 0.254)
			(layers "F.Cu" "F.Mask" "F.Paste")
			(net "P5V_STBY")
		)
		(pad "5" smd rect
			(at -2.39522 -0.48006 90)
			(size 0.7112 0.254)
			(layers "F.Cu" "F.Mask" "F.Paste")
			(net "GND")
		)
		(pad "6" smd rect
			(at -2.39522 -0.029972 90)
			(size 0.7112 0.254)
			(layers "F.Cu" "F.Mask" "F.Paste")
			(net "TP_PVDDQ_KLM_PH2_GL_0")
		)
		(pad "7" smd custom
			(at 0.016764 1.145032 90)
			(size 0.53975 0.53975)
			(layers "F.Cu" "F.Mask" "F.Paste")
			(net "GND")
			(options
				(clearance outline)
				(anchor circle)
			)
			(primitives
				(gr_poly
					(pts
						(xy -2.7051 1.0795) (xy -2.7051 -0.3683) (xy -0.9271 -0.3683) (xy -0.9271 -1.0795) (xy 2.7051 -1.0795)
						(xy 2.7051 1.0795)
					)
					(width 0)
					(fill yes)
				)
			)
		)
		(pad "10" smd rect
			(at -0.008382 2.874772 90)
			(size 4.3434 0.6096)
			(layers "F.Cu" "F.Mask" "F.Paste")
			(net "VR_PVDDQ_KLM_PH2_SW")
		)
		(pad "25" smd rect
			(at 1.548384 -1.283208 90)
			(size 2.3368 2.0066)
			(layers "F.Cu" "F.Mask" "F.Paste")
			(net "VR_FET_SW_P12V_STBY_PVDDQ_KLM")
		)
		(pad "30" smd rect
			(at 2.050034 -2.895092 90)
			(size 0.254 0.7112)
			(layers "F.Cu" "F.Mask" "F.Paste")
			(net "VR_FET_SW_P12V_STBY_PVDDQ_KLM")
		)
		(pad "31" smd rect
			(at 1.599946 -2.895092 90)
			(size 0.254 0.7112)
			(layers "F.Cu" "F.Mask" "F.Paste")
			(net "Net_373")
		)
		(pad "32" smd rect
			(at 1.150112 -2.895092 90)
			(size 0.254 0.7112)
			(layers "F.Cu" "F.Mask" "F.Paste")
			(net "VR_PVDDQ_KLM_PH2_PHASE")
		)
		(pad "33" smd rect
			(at 0.700024 -2.895092 90)
			(size 0.254 0.7112)
			(layers "F.Cu" "F.Mask" "F.Paste")
			(net "VR_PVDDQ_KLM_PH2_BOOT_R")
		)
		(pad "34" smd rect
			(at 0.249936 -2.895092 90)
			(size 0.254 0.7112)
			(layers "F.Cu" "F.Mask" "F.Paste")
			(net "VR_PVDDQ_KLM_PWM2")
		)
		(pad "35" smd rect
			(at -0.199898 -2.895092 90)
			(size 0.254 0.7112)
			(layers "F.Cu" "F.Mask" "F.Paste")
			(net "P5V_STBY")
		)
		(pad "36" smd rect
			(at -0.649986 -2.895092 90)
			(size 0.254 0.7112)
			(layers "F.Cu" "F.Mask" "F.Paste")
			(net "A_TSENSE_PVDDQ_KLM")
		)
		(pad "37" smd rect
			(at -1.100074 -2.895092 90)
			(size 0.254 0.7112)
			(layers "F.Cu" "F.Mask" "F.Paste")
			(net "VR_PVDDQ_KLM_PH2_OCSET")
		)
		(pad "38" smd rect
			(at -1.549908 -2.895092 90)
			(size 0.254 0.7112)
			(layers "F.Cu" "F.Mask" "F.Paste")
			(net "ISENSE_PVDDQ_KLM_PH2_IMON")
		)
		(pad "39" smd rect
			(at -1.999996 -2.895092 90)
			(size 0.254 0.7112)
			(layers "F.Cu" "F.Mask" "F.Paste")
			(net "VR_PVDDQ_KLM_AIREF2")
		)
		(pad "40" smd rect
			(at -0.871728 -1.283208 90)
			(size 1.8034 2.0066)
			(layers "F.Cu" "F.Mask" "F.Paste")
			(net "GND")
		)
		(pad "41" smd rect
			(at -1.533906 0.247904 90)
			(size 0.508 0.3556)
			(layers "F.Cu" "F.Mask" "F.Paste")
			(net "TP_PVDDQ_KLM_PH2_GL_1")
		)
	)
	(footprint ""
		(layer "F.Cu")
		(at 22.4282 -98.19894)
		(property "Reference" "R1C18"
			(at 0 0 0)
			(layer "F.SilkS")
			(hide yes)
			(effects
				(font
					(size 1.27 1.27)
				)
			)
		)
		(property "Value" ""
			(at 0 0 0)
			(layer "F.Fab")
			(effects
				(font
					(size 1.27 1.27)
				)
			)
		)
		(duplicate_pad_numbers_are_jumpers no)
		(fp_rect
			(start -0.2794 0.9906)
			(end 0.2794 -0.1016)
			(stroke
				(width 0)
				(type default)
			)
			(fill no)
			(layer "F.CrtYd")
		)
		(fp_line
			(start -0.2794 -0.1016)
			(end -0.2794 0.9906)
			(stroke
				(width 0.1)
				(type default)
			)
			(layer "F.Fab")
		)
		(fp_line
			(start -0.2794 0.9906)
			(end 0.2794 0.9906)
			(stroke
				(width 0.1)
				(type default)
			)
			(layer "F.Fab")
		)
		(fp_line
			(start 0.2794 -0.1016)
			(end -0.2794 -0.1016)
			(stroke
				(width 0.1)
				(type default)
			)
			(layer "F.Fab")
		)
		(fp_line
			(start 0.2794 0.9906)
			(end 0.2794 -0.1016)
			(stroke
				(width 0.1)
				(type default)
			)
			(layer "F.Fab")
		)
		(pad "1" smd rect
			(at 0 0)
			(size 0.508 0.508)
			(layers "F.Cu" "F.Mask" "F.Paste")
			(net "P3V3_STBY")
		)
		(pad "2" smd rect
			(at 0 0.889)
			(size 0.508 0.508)
			(layers "F.Cu" "F.Mask" "F.Paste")
			(net "PU_VR_PVCCIN_CPU1_IMON")
		)
		(zone
			(layer "F.Cu")
			(hatch none 0.5)
			(connect_pads
				(clearance 0)
			)
			(min_thickness 0.25)
			(keepout
				(tracks not_allowed)
				(vias allowed)
				(pads allowed)
				(copperpour not_allowed)
				(footprints allowed)
			)
			(placement
				(enabled no)
				(sheetname "")
			)
			(fill
				(thermal_gap 0.5)
				(thermal_bridge_width 0.5)
				(island_removal_mode 0)
			)
			(polygon
				(pts
					(xy 22.1742 -97.56394) (xy 22.6822 -97.56394) (xy 22.6822 -97.94494) (xy 22.1742 -97.94494)
				)
			)
		)
		(zone
			(layer "F.Cu")
			(hatch none 0.5)
			(connect_pads
				(clearance 0)
			)
			(min_thickness 0.25)
			(keepout
				(tracks allowed)
				(vias not_allowed)
				(pads allowed)
				(copperpour not_allowed)
				(footprints allowed)
			)
			(placement
				(enabled no)
				(sheetname "")
			)
			(fill
				(thermal_gap 0.5)
				(thermal_bridge_width 0.5)
				(island_removal_mode 0)
			)
			(polygon
				(pts
					(xy 22.1742 -97.56394) (xy 22.6822 -97.56394) (xy 22.6822 -97.94494) (xy 22.1742 -97.94494)
				)
			)
		)
	)
	(footprint ""
		(layer "F.Cu")
		(at 269.559532 -140.208 90)
		(property "Reference" "C5A17"
			(at 1.848866 0.752348 90)
			(unlocked yes)
			(layer "F.SilkS")
			(effects
				(font
					(size 1.27 0.9652)
					(thickness 0.1524)
				)
			)
		)
		(property "Value" ""
			(at 0 0 90)
			(layer "F.Fab")
			(effects
				(font
					(size 1.27 1.27)
				)
			)
		)
		(duplicate_pad_numbers_are_jumpers no)
		(fp_rect
			(start -0.500126 1.598422)
			(end 0.500126 -0.201422)
			(stroke
				(width 0)
				(type default)
			)
			(fill no)
			(layer "F.CrtYd")
		)
		(fp_line
			(start 0.500126 -0.201422)
			(end 0.500126 1.598422)
			(stroke
				(width 0.1)
				(type default)
			)
			(layer "F.Fab")
		)
		(fp_line
			(start -0.500126 -0.201422)
			(end 0.500126 -0.201422)
			(stroke
				(width 0.1)
				(type default)
			)
			(layer "F.Fab")
		)
		(fp_line
			(start 0.500126 1.598422)
			(end -0.500126 1.598422)
			(stroke
				(width 0.1)
				(type default)
			)
			(layer "F.Fab")
		)
		(fp_line
			(start -0.500126 1.598422)
			(end -0.500126 -0.201422)
			(stroke
				(width 0.1)
				(type default)
			)
			(layer "F.Fab")
		)
		(pad "1" smd rect
			(at 0 0)
			(size 0.889 0.9906)
			(layers "F.Cu" "F.Mask" "F.Paste")
			(net "PVDDQ_DEF")
		)
		(pad "2" smd rect
			(at 0 1.397)
			(size 0.889 0.9906)
			(layers "F.Cu" "F.Mask" "F.Paste")
			(net "GND")
		)
		(zone
			(layer "F.Cu")
			(hatch none 0.5)
			(connect_pads
				(clearance 0)
			)
			(min_thickness 0.25)
			(keepout
				(tracks not_allowed)
				(vias allowed)
				(pads allowed)
				(copperpour not_allowed)
				(footprints allowed)
			)
			(placement
				(enabled no)
				(sheetname "")
			)
			(fill
				(thermal_gap 0.5)
				(thermal_bridge_width 0.5)
				(island_removal_mode 0)
			)
			(polygon
				(pts
					(xy 270.512032 -139.7127) (xy 270.512032 -140.7033) (xy 270.004032 -140.7033) (xy 270.004032 -139.7127)
				)
			)
		)
		(zone
			(layer "F.Cu")
			(hatch none 0.5)
			(connect_pads
				(clearance 0)
			)
			(min_thickness 0.25)
			(keepout
				(tracks allowed)
				(vias not_allowed)
				(pads allowed)
				(copperpour not_allowed)
				(footprints allowed)
			)
			(placement
				(enabled no)
				(sheetname "")
			)
			(fill
				(thermal_gap 0.5)
				(thermal_bridge_width 0.5)
				(island_removal_mode 0)
			)
			(polygon
				(pts
					(xy 270.512032 -139.7127) (xy 270.512032 -140.7033) (xy 270.004032 -140.7033) (xy 270.004032 -139.7127)
				)
			)
		)
	)
	(footprint ""
		(layer "F.Cu")
		(at 161.798 -59.309 180)
		(property "Reference" "C3E1"
			(at 0 0 180)
			(layer "F.SilkS")
			(hide yes)
			(effects
				(font
					(size 1.27 1.27)
				)
			)
		)
		(property "Value" ""
			(at 0 0 180)
			(layer "F.Fab")
			(effects
				(font
					(size 1.27 1.27)
				)
			)
		)
		(duplicate_pad_numbers_are_jumpers no)
		(fp_poly
			(pts
				(xy -0.4953 -0.2032) (xy 0.4953 -0.2032) (xy 0.4953 1.6002) (xy -0.4953 1.6002)
			)
			(stroke
				(width 0)
				(type default)
			)
			(fill no)
			(layer "F.CrtYd")
		)
		(fp_line
			(start 0.4953 1.6002)
			(end -0.4953 1.6002)
			(stroke
				(width 0.1)
				(type default)
			)
			(layer "F.Fab")
		)
		(fp_line
			(start 0.4953 -0.2032)
			(end 0.4953 1.6002)
			(stroke
				(width 0.1)
				(type default)
			)
			(layer "F.Fab")
		)
		(fp_line
			(start -0.4953 1.6002)
			(end -0.4953 -0.2032)
			(stroke
				(width 0.1)
				(type default)
			)
			(layer "F.Fab")
		)
		(fp_line
			(start -0.4953 -0.2032)
			(end 0.4953 -0.2032)
			(stroke
				(width 0.1)
				(type default)
			)
			(layer "F.Fab")
		)
		(pad "1" smd rect
			(at 0 0 180)
			(size 0.762 0.889)
			(layers "F.Cu" "F.Mask" "F.Paste")
			(net "PVCCIO_CPU1")
		)
		(pad "2" smd rect
			(at 0 1.397 180)
			(size 0.762 0.889)
			(layers "F.Cu" "F.Mask" "F.Paste")
			(net "GND")
		)
		(zone
			(layer "F.Cu")
			(hatch none 0.5)
			(connect_pads
				(clearance 0)
			)
			(min_thickness 0.25)
			(keepout
				(tracks not_allowed)
				(vias allowed)
				(pads allowed)
				(copperpour not_allowed)
				(footprints allowed)
			)
			(placement
				(enabled no)
				(sheetname "")
			)
			(fill
				(thermal_gap 0.5)
				(thermal_bridge_width 0.5)
				(island_removal_mode 0)
			)
			(polygon
				(pts
					(xy 162.179 -59.7535) (xy 161.417 -59.7535) (xy 161.417 -60.2615) (xy 162.179 -60.2615)
				)
			)
		)
	)
	(footprint ""
		(layer "F.Cu")
		(at 157.97022 -125.1077 90)
		(property "Reference" "C3B4"
			(at 0 0 90)
			(layer "F.SilkS")
			(hide yes)
			(effects
				(font
					(size 1.27 1.27)
				)
			)
		)
		(property "Value" ""
			(at 0 0 90)
			(layer "F.Fab")
			(effects
				(font
					(size 1.27 1.27)
				)
			)
		)
		(duplicate_pad_numbers_are_jumpers no)
		(fp_poly
			(pts
				(xy 0.3048 -0.1016) (xy 0.3048 0.9906) (xy -0.3048 0.9906) (xy -0.3048 -0.1016)
			)
			(stroke
				(width 0)
				(type default)
			)
			(fill no)
			(layer "F.CrtYd")
		)
		(fp_line
			(start 0.3048 -0.1016)
			(end -0.3048 -0.1016)
			(stroke
				(width 0.1)
				(type default)
			)
			(layer "F.Fab")
		)
		(fp_line
			(start -0.3048 -0.1016)
			(end -0.3048 0.9906)
			(stroke
				(width 0.1)
				(type default)
			)
			(layer "F.Fab")
		)
		(fp_line
			(start 0.3048 0.9906)
			(end 0.3048 -0.1016)
			(stroke
				(width 0.1)
				(type default)
			)
			(layer "F.Fab")
		)
		(fp_line
			(start -0.3048 0.9906)
			(end 0.3048 0.9906)
			(stroke
				(width 0.1)
				(type default)
			)
			(layer "F.Fab")
		)
		(pad "1" smd rect
			(at 0 0 90)
			(size 0.508 0.508)
			(layers "F.Cu" "F.Mask" "F.Paste")
			(net "PVCCIO_CPU1")
		)
		(pad "2" smd rect
			(at 0 0.889 90)
			(size 0.508 0.508)
			(layers "F.Cu" "F.Mask" "F.Paste")
			(net "GND")
		)
		(zone
			(layer "F.Cu")
			(hatch none 0.5)
			(connect_pads
				(clearance 0)
			)
			(min_thickness 0.25)
			(keepout
				(tracks allowed)
				(vias not_allowed)
				(pads allowed)
				(copperpour not_allowed)
				(footprints allowed)
			)
			(placement
				(enabled no)
				(sheetname "")
			)
			(fill
				(thermal_gap 0.5)
				(thermal_bridge_width 0.5)
				(island_removal_mode 0)
			)
			(polygon
				(pts
					(xy 158.22422 -124.8537) (xy 158.22422 -125.3617) (xy 158.60522 -125.3617) (xy 158.60522 -124.8537)
				)
			)
		)
		(zone
			(layer "F.Cu")
			(hatch none 0.5)
			(connect_pads
				(clearance 0)
			)
			(min_thickness 0.25)
			(keepout
				(tracks not_allowed)
				(vias allowed)
				(pads allowed)
				(copperpour not_allowed)
				(footprints allowed)
			)
			(placement
				(enabled no)
				(sheetname "")
			)
			(fill
				(thermal_gap 0.5)
				(thermal_bridge_width 0.5)
				(island_removal_mode 0)
			)
			(polygon
				(pts
					(xy 158.60522 -124.8537) (xy 158.60522 -125.3617) (xy 158.22422 -125.3617) (xy 158.22422 -124.8537)
				)
			)
		)
	)
)
